(kicad_pcb
	(version 20260206)
	(generator "pcbnew")
	(generator_version "10.0")
	(general
		(thickness 1.6)
		(legacy_teardrops no)
	)
	(paper "A4")
	(title_block
		(title "Bryce Canyon_F.DPB_16315-1-OCP.brd")
		(comment 1 "Bryce Canyon / footprints 13-18 of 2223")
	)
	(layers
		(0 "F.Cu" signal "TOP")
		(4 "In1.Cu" signal "L2GND")
		(6 "In2.Cu" signal "L3")
		(8 "In3.Cu" signal "L4GND")
		(10 "In4.Cu" signal "L5")
		(12 "In5.Cu" signal "L6VCC")
		(14 "In6.Cu" signal "L7VCC")
		(16 "In7.Cu" signal "L8")
		(18 "In8.Cu" signal "L9GND")
		(20 "In9.Cu" signal "L10")
		(22 "In10.Cu" signal "L11GND")
		(2 "B.Cu" signal "BOTTOM")
		(9 "F.Adhes" user "F.Adhesive")
		(11 "B.Adhes" user "B.Adhesive")
		(13 "F.Paste" user "Package Geometry/Pastemask Top")
		(15 "B.Paste" user "Package Geometry/Pastemask Bottom")
		(5 "F.SilkS" user "Ref Des/Silkscreen Top")
		(7 "B.SilkS" user "Ref Des/Silkscreen Bottom")
		(1 "F.Mask" user "Board Geometry/Soldermask Top")
		(3 "B.Mask" user "Board Geometry/Soldermask Bottom")
		(17 "Dwgs.User" user "User.Drawings")
		(19 "Cmts.User" user "User.Comments")
		(21 "Eco1.User" user "User.Eco1")
		(23 "Eco2.User" user "User.Eco2")
		(25 "Edge.Cuts" user "Board Geometry/Outline")
		(27 "Margin" user)
		(31 "F.CrtYd" user "Package Geometry/Place Bound Top")
		(29 "B.CrtYd" user "Package Geometry/Place Bound Bottom")
		(35 "F.Fab" user "Ref Des/Assembly Top")
		(33 "B.Fab" user "Ref Des/Assembly Bottom")
	)
	(footprint ""
		(layer "F.Cu")
		(at 146.755866 -143.848074 -90)
		(property "Reference" "R1058"
			(at 0 0 270)
			(layer "F.SilkS")
			(hide yes)
			(effects
				(font
					(size 1.27 1.27)
				)
			)
		)
		(property "Value" "100KR2F-L1-GP"
			(at 0.064008 -3.993896 270)
			(unlocked yes)
			(layer "F.Fab")
			(hide yes)
			(effects
				(font
					(size 1.016 1.016)
					(thickness 0.1524)
				)
			)
		)
		(property "Device Type" "R402H16"
			(at 0.064008 -5.517896 270)
			(unlocked yes)
			(layer "F.Fab")
			(hide yes)
			(effects
				(font
					(size 1.016 1.016)
					(thickness 0.1524)
				)
			)
		)
		(duplicate_pad_numbers_are_jumpers no)
		(fp_line
			(start -0.508 -0.9398)
			(end -0.508 0.9398)
			(stroke
				(width 0.1524)
				(type default)
			)
			(layer "F.SilkS")
		)
		(fp_line
			(start 0.508 -0.9398)
			(end -0.508 -0.9398)
			(stroke
				(width 0.1524)
				(type default)
			)
			(layer "F.SilkS")
		)
		(fp_rect
			(start -0.508 0.9398)
			(end 0.508 -0.9398)
			(stroke
				(width 0)
				(type default)
			)
			(fill no)
			(layer "F.CrtYd")
		)
		(fp_rect
			(start -0.508 0.9398)
			(end 0.508 -0.9398)
			(stroke
				(width 0)
				(type default)
			)
			(fill no)
			(layer "F.Fab")
		)
		(pad "1" smd custom
			(at 0 -0.4445 270)
			(size 0.1397 0.1397)
			(layers "F.Cu" "F.Mask" "F.Paste")
			(net "MB0_VCAP_R")
			(options
				(clearance outline)
				(anchor circle)
			)
			(primitives
				(gr_poly
					(pts
						(arc
							(start -0.1778 -0.2794)
							(mid -0.249642 -0.249642)
							(end -0.2794 -0.1778)
						)
						(arc
							(start -0.2794 0.1778)
							(mid -0.249642 0.249642)
							(end -0.1778 0.2794)
						)
						(arc
							(start 0.1778 0.2794)
							(mid 0.249642 0.249642)
							(end 0.2794 0.1778)
						)
						(arc
							(start 0.2794 -0.1778)
							(mid 0.249642 -0.249642)
							(end 0.1778 -0.2794)
						)
					)
					(width 0)
					(fill yes)
				)
			)
		)
		(pad "2" smd custom
			(at 0 0.4445 270)
			(size 0.1397 0.1397)
			(layers "F.Cu" "F.Mask" "F.Paste")
			(net "MB0_ISET_R")
			(options
				(clearance outline)
				(anchor circle)
			)
			(primitives
				(gr_poly
					(pts
						(arc
							(start -0.1778 -0.2794)
							(mid -0.249642 -0.249642)
							(end -0.2794 -0.1778)
						)
						(arc
							(start -0.2794 0.1778)
							(mid -0.249642 0.249642)
							(end -0.1778 0.2794)
						)
						(arc
							(start 0.1778 0.2794)
							(mid 0.249642 0.249642)
							(end 0.2794 0.1778)
						)
						(arc
							(start 0.2794 -0.1778)
							(mid 0.249642 -0.249642)
							(end 0.1778 -0.2794)
						)
					)
					(width 0)
					(fill yes)
				)
			)
		)
	)
	(footprint ""
		(layer "F.Cu")
		(at 334.899 -52.872894 -90)
		(property "Reference" "Q180"
			(at 0 0 270)
			(layer "F.SilkS")
			(hide yes)
			(effects
				(font
					(size 1.27 1.27)
				)
			)
		)
		(property "Value" "AO4406AL-GP"
			(at -3.707384 -1.5367 270)
			(unlocked yes)
			(layer "F.Fab")
			(hide yes)
			(effects
				(font
					(size 1.016 1.016)
					(thickness 0.1524)
				)
			)
		)
		(property "Device Type" "SOIC8H69"
			(at -3.707384 -3.0607 270)
			(unlocked yes)
			(layer "F.Fab")
			(hide yes)
			(effects
				(font
					(size 1.016 1.016)
					(thickness 0.1524)
				)
			)
		)
		(duplicate_pad_numbers_are_jumpers no)
		(fp_line
			(start -2.6289 3.4417)
			(end -2.6289 1.4732)
			(stroke
				(width 0.381)
				(type default)
			)
			(layer "F.SilkS")
		)
		(fp_line
			(start -2.7432 1.4224)
			(end -2.6416 1.4224)
			(stroke
				(width 0.1524)
				(type default)
			)
			(layer "F.SilkS")
		)
		(fp_line
			(start -2.7432 1.4224)
			(end 2.1336 1.4224)
			(stroke
				(width 0.1524)
				(type default)
			)
			(layer "F.SilkS")
		)
		(fp_line
			(start 2.1336 1.4224)
			(end 2.1336 -1.4224)
			(stroke
				(width 0.1524)
				(type default)
			)
			(layer "F.SilkS")
		)
		(fp_line
			(start -2.1844 -0.0508)
			(end -2.7178 0.508)
			(stroke
				(width 0.1524)
				(type default)
			)
			(layer "F.SilkS")
		)
		(fp_line
			(start -2.7178 -0.508)
			(end -2.1844 -0.0508)
			(stroke
				(width 0.1524)
				(type default)
			)
			(layer "F.SilkS")
		)
		(fp_line
			(start -2.7432 -1.4224)
			(end -2.7432 1.4224)
			(stroke
				(width 0.1524)
				(type default)
			)
			(layer "F.SilkS")
		)
		(fp_line
			(start 2.1336 -1.4224)
			(end -2.7432 -1.4224)
			(stroke
				(width 0.1524)
				(type default)
			)
			(layer "F.SilkS")
		)
		(fp_poly
			(pts
				(xy -2.2098 -1.4224) (xy -2.2098 1.4224) (xy 2.2098 1.4224) (xy 2.2098 -1.4224)
			)
			(stroke
				(width 0)
				(type default)
			)
			(fill yes)
			(layer "F.SilkS")
		)
		(fp_rect
			(start -2.450084 2.999994)
			(end 2.450084 -2.999994)
			(stroke
				(width 0)
				(type default)
			)
			(fill no)
			(layer "F.CrtYd")
		)
		(fp_poly
			(pts
				(xy -2.8194 3.6322) (xy -2.8194 -3.6322) (xy 2.8194 -3.6322) (xy 2.8194 1.18364) (xy 2.450084 1.18364)
				(xy 2.450084 -2.999994) (xy -2.450084 -2.999994) (xy -2.450084 2.999994) (xy 2.450084 2.999994)
				(xy 2.450084 1.18618) (xy 2.8194 1.18618) (xy 2.8194 3.6322)
			)
			(stroke
				(width 0)
				(type default)
			)
			(fill no)
			(layer "F.CrtYd")
		)
		(fp_rect
			(start -2.8194 3.6322)
			(end 2.8194 -3.6322)
			(stroke
				(width 0)
				(type default)
			)
			(fill no)
			(layer "F.Fab")
		)
		(pad "1" smd rect
			(at -1.905 2.54 270)
			(size 0.635 1.651)
			(layers "F.Cu" "F.Mask" "F.Paste")
			(net "P5V_HDD30")
		)
		(pad "2" smd rect
			(at -0.635 2.54 270)
			(size 0.635 1.651)
			(layers "F.Cu" "F.Mask" "F.Paste")
			(net "P5V_HDD30")
		)
		(pad "3" smd rect
			(at 0.635 2.54 270)
			(size 0.635 1.651)
			(layers "F.Cu" "F.Mask" "F.Paste")
			(net "P5V_HDD30")
		)
		(pad "4" smd rect
			(at 1.905 2.54 270)
			(size 0.635 1.651)
			(layers "F.Cu" "F.Mask" "F.Paste")
			(net "SW_HDD_P30")
		)
		(pad "5" smd rect
			(at 1.905 -2.54 270)
			(size 0.635 1.651)
			(layers "F.Cu" "F.Mask" "F.Paste")
			(net "P5V_A_4")
		)
		(pad "6" smd rect
			(at 0.635 -2.54 270)
			(size 0.635 1.651)
			(layers "F.Cu" "F.Mask" "F.Paste")
			(net "P5V_A_4")
		)
		(pad "7" smd rect
			(at -0.635 -2.54 270)
			(size 0.635 1.651)
			(layers "F.Cu" "F.Mask" "F.Paste")
			(net "P5V_A_4")
		)
		(pad "8" smd rect
			(at -1.905 -2.54 270)
			(size 0.635 1.651)
			(layers "F.Cu" "F.Mask" "F.Paste")
			(net "P5V_A_4")
		)
	)
	(footprint ""
		(layer "F.Cu")
		(at 398.81175 -45.735494 180)
		(property "Reference" "R883"
			(at 0 0 180)
			(layer "F.SilkS")
			(hide yes)
			(effects
				(font
					(size 1.27 1.27)
				)
			)
		)
		(property "Value" "0R2J-2-GP"
			(at 0.064008 -3.993896 180)
			(unlocked yes)
			(layer "F.Fab")
			(hide yes)
			(effects
				(font
					(size 1.016 1.016)
					(thickness 0.1524)
				)
			)
		)
		(property "Device Type" "R402H16"
			(at 0.064008 -5.517896 180)
			(unlocked yes)
			(layer "F.Fab")
			(hide yes)
			(effects
				(font
					(size 1.016 1.016)
					(thickness 0.1524)
				)
			)
		)
		(duplicate_pad_numbers_are_jumpers no)
		(fp_line
			(start 0.508 -0.9398)
			(end -0.508 -0.9398)
			(stroke
				(width 0.1524)
				(type default)
			)
			(layer "F.SilkS")
		)
		(fp_line
			(start -0.508 -0.9398)
			(end -0.508 0.9398)
			(stroke
				(width 0.1524)
				(type default)
			)
			(layer "F.SilkS")
		)
		(fp_rect
			(start -0.508 0.9398)
			(end 0.508 -0.9398)
			(stroke
				(width 0)
				(type default)
			)
			(fill no)
			(layer "F.CrtYd")
		)
		(fp_rect
			(start -0.508 0.9398)
			(end 0.508 -0.9398)
			(stroke
				(width 0)
				(type default)
			)
			(fill no)
			(layer "F.Fab")
		)
		(pad "1" smd custom
			(at 0 -0.4445 180)
			(size 0.1397 0.1397)
			(layers "F.Cu" "F.Mask" "F.Paste")
			(net "SW_HDD_G32")
			(options
				(clearance outline)
				(anchor circle)
			)
			(primitives
				(gr_poly
					(pts
						(arc
							(start -0.1778 -0.2794)
							(mid -0.249642 -0.249642)
							(end -0.2794 -0.1778)
						)
						(arc
							(start -0.2794 0.1778)
							(mid -0.249642 0.249642)
							(end -0.1778 0.2794)
						)
						(arc
							(start 0.1778 0.2794)
							(mid 0.249642 0.249642)
							(end 0.2794 0.1778)
						)
						(arc
							(start 0.2794 -0.1778)
							(mid 0.249642 -0.249642)
							(end 0.1778 -0.2794)
						)
					)
					(width 0)
					(fill yes)
				)
			)
		)
		(pad "2" smd custom
			(at 0 0.4445 180)
			(size 0.1397 0.1397)
			(layers "F.Cu" "F.Mask" "F.Paste")
			(net "SW_HDD_R32")
			(options
				(clearance outline)
				(anchor circle)
			)
			(primitives
				(gr_poly
					(pts
						(arc
							(start -0.1778 -0.2794)
							(mid -0.249642 -0.249642)
							(end -0.2794 -0.1778)
						)
						(arc
							(start -0.2794 0.1778)
							(mid -0.249642 0.249642)
							(end -0.1778 0.2794)
						)
						(arc
							(start 0.1778 0.2794)
							(mid 0.249642 0.249642)
							(end 0.2794 0.1778)
						)
						(arc
							(start 0.2794 -0.1778)
							(mid 0.249642 -0.249642)
							(end 0.1778 -0.2794)
						)
					)
					(width 0)
					(fill yes)
				)
			)
		)
	)
	(footprint ""
		(layer "F.Cu")
		(at 172.517308 -27.99334 90)
		(property "Reference" "U30"
			(at 0 0 90)
			(layer "F.SilkS")
			(hide yes)
			(effects
				(font
					(size 1.27 1.27)
				)
			)
		)
		(property "Value" "SNLVC1G126DCKR-GP"
			(at -2.3368 -8.6868 90)
			(unlocked yes)
			(layer "F.Fab")
			(hide yes)
			(effects
				(font
					(size 1.016 1.016)
					(thickness 0.1524)
				)
			)
		)
		(property "Device Type" "SC70-5H44"
			(at -2.3114 -10.414 90)
			(unlocked yes)
			(layer "F.Fab")
			(hide yes)
			(effects
				(font
					(size 1.016 1.016)
					(thickness 0.1524)
				)
			)
		)
		(duplicate_pad_numbers_are_jumpers no)
		(fp_line
			(start 1.3843 -1.8034)
			(end 1.3843 -1.1176)
			(stroke
				(width 0.3302)
				(type default)
			)
			(layer "F.SilkS")
		)
		(fp_line
			(start 0.6604 -1.8034)
			(end 1.3843 -1.8034)
			(stroke
				(width 0.3302)
				(type default)
			)
			(layer "F.SilkS")
		)
		(fp_line
			(start 1.27 -1.7018)
			(end 1.27 1.7018)
			(stroke
				(width 0.1524)
				(type default)
			)
			(layer "F.SilkS")
		)
		(fp_line
			(start -1.27 -1.7018)
			(end 1.27 -1.7018)
			(stroke
				(width 0.1524)
				(type default)
			)
			(layer "F.SilkS")
		)
		(fp_line
			(start 1.27 1.7018)
			(end -1.27 1.7018)
			(stroke
				(width 0.1524)
				(type default)
			)
			(layer "F.SilkS")
		)
		(fp_line
			(start -1.27 1.7018)
			(end -1.27 -1.7018)
			(stroke
				(width 0.1524)
				(type default)
			)
			(layer "F.SilkS")
		)
		(fp_rect
			(start -1.524 1.9558)
			(end 1.524 -1.9558)
			(stroke
				(width 0)
				(type default)
			)
			(fill no)
			(layer "F.CrtYd")
		)
		(fp_poly
			(pts
				(xy -1.524 -1.9558) (xy 1.524 -1.9558) (xy 1.524 1.9558) (xy -1.524 1.9558)
			)
			(stroke
				(width 0)
				(type default)
			)
			(fill no)
			(layer "F.Fab")
		)
		(pad "1" smd rect
			(at 0.65024 -0.8255 90)
			(size 0.4064 1.2192)
			(layers "F.Cu" "F.Mask" "F.Paste")
			(net "P3V3_STBY_A")
		)
		(pad "2" smd rect
			(at 0 -0.8255 90)
			(size 0.4064 1.2192)
			(layers "F.Cu" "F.Mask" "F.Paste")
			(net "SYS_A_RESET_N")
		)
		(pad "3" smd rect
			(at -0.65024 -0.8255 90)
			(size 0.4064 1.2192)
			(layers "F.Cu" "F.Mask" "F.Paste")
			(net "GND")
		)
		(pad "4" smd rect
			(at -0.65024 0.8255 90)
			(size 0.4064 1.2192)
			(layers "F.Cu" "F.Mask" "F.Paste")
			(net "SYS_A_RESET_BUFFER_N")
		)
		(pad "5" smd rect
			(at 0.65024 0.8255 90)
			(size 0.4064 1.2192)
			(layers "F.Cu" "F.Mask" "F.Paste")
			(net "P3V3_STBY_A")
		)
	)
	(footprint ""
		(layer "F.Cu")
		(at 20.430998 -62.778894 -90)
		(property "Reference" "C352"
			(at 0 0 270)
			(layer "F.SilkS")
			(hide yes)
			(effects
				(font
					(size 1.27 1.27)
				)
			)
		)
		(property "Value" "SC1U16V3KX-5GP"
			(at 0 -2.8194 270)
			(unlocked yes)
			(layer "F.Fab")
			(hide yes)
			(effects
				(font
					(size 1.016 1.016)
					(thickness 0.1524)
				)
			)
		)
		(property "Device Type" "C603H36"
			(at 0 -4.3434 270)
			(unlocked yes)
			(layer "F.Fab")
			(hide yes)
			(effects
				(font
					(size 1.016 1.016)
					(thickness 0.1524)
				)
			)
		)
		(duplicate_pad_numbers_are_jumpers no)
		(fp_line
			(start 0.508 0)
			(end -0.508 0)
			(stroke
				(width 0.2032)
				(type default)
			)
			(layer "F.SilkS")
		)
		(fp_rect
			(start -0.5842 1.3335)
			(end 0.5842 -1.3335)
			(stroke
				(width 0)
				(type default)
			)
			(fill no)
			(layer "F.CrtYd")
		)
		(fp_rect
			(start -0.5842 1.3335)
			(end 0.5842 -1.3335)
			(stroke
				(width 0)
				(type default)
			)
			(fill no)
			(layer "F.Fab")
		)
		(pad "1" smd custom
			(at 0 -0.762 270)
			(size 0.2159 0.2159)
			(layers "F.Cu" "F.Mask" "F.Paste")
			(net "P5V_HDD24")
			(options
				(clearance outline)
				(anchor circle)
			)
			(primitives
				(gr_poly
					(pts
						(arc
							(start -0.3302 -0.4318)
							(mid -0.402042 -0.402042)
							(end -0.4318 -0.3302)
						)
						(arc
							(start -0.4318 0.3302)
							(mid -0.402042 0.402042)
							(end -0.3302 0.4318)
						)
						(arc
							(start 0.3302 0.4318)
							(mid 0.402042 0.402042)
							(end 0.4318 0.3302)
						)
						(arc
							(start 0.4318 -0.3302)
							(mid 0.402042 -0.402042)
							(end 0.3302 -0.4318)
						)
					)
					(width 0)
					(fill yes)
				)
			)
		)
		(pad "2" smd custom
			(at 0 0.762 270)
			(size 0.2159 0.2159)
			(layers "F.Cu" "F.Mask" "F.Paste")
			(net "GND")
			(options
				(clearance outline)
				(anchor circle)
			)
			(primitives
				(gr_poly
					(pts
						(arc
							(start -0.3302 -0.4318)
							(mid -0.402042 -0.402042)
							(end -0.4318 -0.3302)
						)
						(arc
							(start -0.4318 0.3302)
							(mid -0.402042 0.402042)
							(end -0.3302 0.4318)
						)
						(arc
							(start 0.3302 0.4318)
							(mid 0.402042 0.402042)
							(end 0.4318 0.3302)
						)
						(arc
							(start 0.4318 -0.3302)
							(mid 0.402042 -0.402042)
							(end 0.3302 -0.4318)
						)
					)
					(width 0)
					(fill yes)
				)
			)
		)
	)
	(footprint ""
		(layer "F.Cu")
		(at 246.507 -231.14 180)
		(property "Reference" "R86"
			(at 0 0 180)
			(layer "F.SilkS")
			(hide yes)
			(effects
				(font
					(size 1.27 1.27)
				)
			)
		)
		(property "Value" "4K7R2F-GP"
			(at 0.064008 -3.993896 180)
			(unlocked yes)
			(layer "F.Fab")
			(hide yes)
			(effects
				(font
					(size 1.016 1.016)
					(thickness 0.1524)
				)
			)
		)
		(property "Device Type" "R402H16"
			(at 0.064008 -5.517896 180)
			(unlocked yes)
			(layer "F.Fab")
			(hide yes)
			(effects
				(font
					(size 1.016 1.016)
					(thickness 0.1524)
				)
			)
		)
		(duplicate_pad_numbers_are_jumpers no)
		(fp_line
			(start 0.508 -0.9398)
			(end -0.508 -0.9398)
			(stroke
				(width 0.1524)
				(type default)
			)
			(layer "F.SilkS")
		)
		(fp_line
			(start -0.508 -0.9398)
			(end -0.508 0.9398)
			(stroke
				(width 0.1524)
				(type default)
			)
			(layer "F.SilkS")
		)
		(fp_rect
			(start -0.508 0.9398)
			(end 0.508 -0.9398)
			(stroke
				(width 0)
				(type default)
			)
			(fill no)
			(layer "F.CrtYd")
		)
		(fp_rect
			(start -0.508 0.9398)
			(end 0.508 -0.9398)
			(stroke
				(width 0)
				(type default)
			)
			(fill no)
			(layer "F.Fab")
		)
		(pad "1" smd custom
			(at 0 -0.4445 180)
			(size 0.1397 0.1397)
			(layers "F.Cu" "F.Mask" "F.Paste")
			(net "P3V3_STBY_A")
			(options
				(clearance outline)
				(anchor circle)
			)
			(primitives
				(gr_poly
					(pts
						(arc
							(start -0.1778 -0.2794)
							(mid -0.249642 -0.249642)
							(end -0.2794 -0.1778)
						)
						(arc
							(start -0.2794 0.1778)
							(mid -0.249642 0.249642)
							(end -0.1778 0.2794)
						)
						(arc
							(start 0.1778 0.2794)
							(mid 0.249642 0.249642)
							(end 0.2794 0.1778)
						)
						(arc
							(start 0.2794 -0.1778)
							(mid 0.249642 -0.249642)
							(end 0.1778 -0.2794)
						)
					)
					(width 0)
					(fill yes)
				)
			)
		)
		(pad "2" smd custom
			(at 0 0.4445 180)
			(size 0.1397 0.1397)
			(layers "F.Cu" "F.Mask" "F.Paste")
			(net "IO_EXP2_A2")
			(options
				(clearance outline)
				(anchor circle)
			)
			(primitives
				(gr_poly
					(pts
						(arc
							(start -0.1778 -0.2794)
							(mid -0.249642 -0.249642)
							(end -0.2794 -0.1778)
						)
						(arc
							(start -0.2794 0.1778)
							(mid -0.249642 0.249642)
							(end -0.1778 0.2794)
						)
						(arc
							(start 0.1778 0.2794)
							(mid 0.249642 0.249642)
							(end 0.2794 0.1778)
						)
						(arc
							(start 0.2794 -0.1778)
							(mid 0.249642 -0.249642)
							(end 0.1778 -0.2794)
						)
					)
					(width 0)
					(fill yes)
				)
			)
		)
	)
)
